(kicad_pcb
	(version 20260206)
	(generator "pcbnew")
	(generator_version "10.0")
	(general
		(thickness 1.6)
		(legacy_teardrops no)
	)
	(paper "A4")
	(title_block
		(title "panther-plus-userver — 13130-1b_20150205.brd")
		(comment 1 "Honey Badger (Wiwynn) / footprints 161-166 of 1509")
	)
	(layers
		(0 "F.Cu" signal "TOP")
		(4 "In1.Cu" signal "L2")
		(6 "In2.Cu" signal "L3")
		(8 "In3.Cu" signal "L4")
		(10 "In4.Cu" signal "L5")
		(12 "In5.Cu" signal "L6")
		(14 "In6.Cu" signal "L7")
		(16 "In7.Cu" signal "L8")
		(18 "In8.Cu" signal "L9")
		(20 "In9.Cu" signal "L10")
		(22 "In10.Cu" signal "L11")
		(2 "B.Cu" signal "BOTTOM")
		(9 "F.Adhes" user "F.Adhesive")
		(11 "B.Adhes" user "B.Adhesive")
		(13 "F.Paste" user "Package Geometry/Pastemask Top")
		(15 "B.Paste" user "Package Geometry/Pastemask Bottom")
		(5 "F.SilkS" user "Ref Des/Silkscreen Top")
		(7 "B.SilkS" user "Ref Des/Silkscreen Bottom")
		(1 "F.Mask" user "Board Geometry/Soldermask Top")
		(3 "B.Mask" user "Board Geometry/Soldermask Bottom")
		(17 "Dwgs.User" user "User.Drawings")
		(19 "Cmts.User" user "User.Comments")
		(21 "Eco1.User" user "User.Eco1")
		(23 "Eco2.User" user "User.Eco2")
		(25 "Edge.Cuts" user "Board Geometry/Outline")
		(27 "Margin" user)
		(31 "F.CrtYd" user "Package Geometry/Place Bound Top")
		(29 "B.CrtYd" user "Package Geometry/Place Bound Bottom")
		(35 "F.Fab" user "Ref Des/Assembly Top")
		(33 "B.Fab" user "Ref Des/Assembly Bottom")
	)
	(footprint ""
		(layer "F.Cu")
		(at 11.43 -51.7398 90)
		(property "Reference" "C59"
			(at 0 0 90)
			(layer "F.SilkS")
			(hide yes)
			(effects
				(font
					(size 1.27 1.27)
				)
			)
		)
		(property "Value" "SCD1U16V2KX-3GP"
			(at 1.1811 -2.7051 90)
			(unlocked yes)
			(layer "F.Fab")
			(hide yes)
			(effects
				(font
					(size 1.016 1.016)
					(thickness 0.1524)
				)
			)
		)
		(property "Device Type" "C402H22"
			(at 1.1811 -4.2291 90)
			(unlocked yes)
			(layer "F.Fab")
			(hide yes)
			(effects
				(font
					(size 1.016 1.016)
					(thickness 0.1524)
				)
			)
		)
		(duplicate_pad_numbers_are_jumpers no)
		(fp_rect
			(start -0.381 0.7366)
			(end 0.381 -0.7366)
			(stroke
				(width 0)
				(type default)
			)
			(fill no)
			(layer "F.CrtYd")
		)
		(fp_rect
			(start -0.381 0.7366)
			(end 0.381 -0.7366)
			(stroke
				(width 0)
				(type default)
			)
			(fill no)
			(layer "F.Fab")
		)
		(pad "1" smd custom
			(at 0 -0.4572 90)
			(size 0.1143 0.1143)
			(layers "F.Cu" "F.Mask" "F.Paste")
			(net "P2E_CPU_NGFF_TX_DN12")
			(options
				(clearance outline)
				(anchor circle)
			)
			(primitives
				(gr_poly
					(pts
						(arc
							(start -0.254 -0.1778)
							(mid -0.239121 -0.213721)
							(end -0.2032 -0.2286)
						)
						(arc
							(start 0.2032 -0.2286)
							(mid 0.239121 -0.213721)
							(end 0.254 -0.1778)
						)
						(arc
							(start 0.254 0.1778)
							(mid 0.239121 0.213721)
							(end 0.2032 0.2286)
						)
						(arc
							(start -0.2032 0.2286)
							(mid -0.239121 0.213721)
							(end -0.254 0.1778)
						)
					)
					(width 0)
					(fill yes)
				)
			)
		)
		(pad "2" smd custom
			(at 0 0.4572 90)
			(size 0.1143 0.1143)
			(layers "F.Cu" "F.Mask" "F.Paste")
			(net "P2E_CPU_NGFF_C_TX_DN12")
			(options
				(clearance outline)
				(anchor circle)
			)
			(primitives
				(gr_poly
					(pts
						(arc
							(start -0.254 -0.1778)
							(mid -0.239121 -0.213721)
							(end -0.2032 -0.2286)
						)
						(arc
							(start 0.2032 -0.2286)
							(mid 0.239121 -0.213721)
							(end 0.254 -0.1778)
						)
						(arc
							(start 0.254 0.1778)
							(mid 0.239121 0.213721)
							(end 0.2032 0.2286)
						)
						(arc
							(start -0.2032 0.2286)
							(mid -0.239121 0.213721)
							(end -0.254 0.1778)
						)
					)
					(width 0)
					(fill yes)
				)
			)
		)
	)
	(footprint ""
		(layer "F.Cu")
		(at 4.699 -44.45)
		(property "Reference" "R4"
			(at 0 0 0)
			(layer "F.SilkS")
			(hide yes)
			(effects
				(font
					(size 1.27 1.27)
				)
			)
		)
		(property "Value" "0R2J-2-GP"
			(at 0.064008 -3.993896 0)
			(unlocked yes)
			(layer "F.Fab")
			(hide yes)
			(effects
				(font
					(size 1.016 1.016)
					(thickness 0.1524)
				)
			)
		)
		(property "Device Type" "R402H16"
			(at 0.064008 -5.517896 0)
			(unlocked yes)
			(layer "F.Fab")
			(hide yes)
			(effects
				(font
					(size 1.016 1.016)
					(thickness 0.1524)
				)
			)
		)
		(duplicate_pad_numbers_are_jumpers no)
		(fp_rect
			(start -0.381 0.8382)
			(end 0.381 -0.8382)
			(stroke
				(width 0)
				(type default)
			)
			(fill no)
			(layer "F.CrtYd")
		)
		(fp_rect
			(start -0.381 0.8382)
			(end 0.381 -0.8382)
			(stroke
				(width 0)
				(type default)
			)
			(fill no)
			(layer "F.Fab")
		)
		(pad "1" smd custom
			(at 0 -0.4318)
			(size 0.127 0.127)
			(layers "F.Cu" "F.Mask" "F.Paste")
			(net "SMB_HOST_LV_DATA")
			(options
				(clearance outline)
				(anchor circle)
			)
			(primitives
				(gr_poly
					(pts
						(arc
							(start -0.2032 -0.2794)
							(mid -0.239121 -0.264521)
							(end -0.254 -0.2286)
						)
						(arc
							(start -0.254 0.2286)
							(mid -0.239121 0.264521)
							(end -0.2032 0.2794)
						)
						(arc
							(start 0.2032 0.2794)
							(mid 0.239121 0.264521)
							(end 0.254 0.2286)
						)
						(arc
							(start 0.254 -0.2286)
							(mid 0.239121 -0.264521)
							(end 0.2032 -0.2794)
						)
					)
					(width 0)
					(fill yes)
				)
			)
		)
		(pad "2" smd custom
			(at 0 0.4318)
			(size 0.127 0.127)
			(layers "F.Cu" "F.Mask" "F.Paste")
			(net "TEMP_1_DATA")
			(options
				(clearance outline)
				(anchor circle)
			)
			(primitives
				(gr_poly
					(pts
						(arc
							(start -0.2032 -0.2794)
							(mid -0.239121 -0.264521)
							(end -0.254 -0.2286)
						)
						(arc
							(start -0.254 0.2286)
							(mid -0.239121 0.264521)
							(end -0.2032 0.2794)
						)
						(arc
							(start 0.2032 0.2794)
							(mid 0.239121 0.264521)
							(end 0.254 0.2286)
						)
						(arc
							(start 0.254 -0.2286)
							(mid 0.239121 -0.264521)
							(end 0.2032 -0.2794)
						)
					)
					(width 0)
					(fill yes)
				)
			)
		)
	)
	(footprint ""
		(layer "F.Cu")
		(at 65.4558 -63.754 180)
		(property "Reference" "PC136"
			(at 0 0 180)
			(layer "F.SilkS")
			(hide yes)
			(effects
				(font
					(size 1.27 1.27)
				)
			)
		)
		(property "Value" "SC47U6D3V5MX-1-GP"
			(at -0.0762 -6.1214 180)
			(unlocked yes)
			(layer "F.Fab")
			(hide yes)
			(effects
				(font
					(size 1.016 1.016)
					(thickness 0.1524)
				)
			)
		)
		(property "Device Type" "C805H54"
			(at -0.0762 -8.1534 180)
			(unlocked yes)
			(layer "F.Fab")
			(hide yes)
			(effects
				(font
					(size 1.016 1.016)
					(thickness 0.1524)
				)
			)
		)
		(duplicate_pad_numbers_are_jumpers no)
		(fp_line
			(start 0.6096 0)
			(end -0.6096 0)
			(stroke
				(width 0.3048)
				(type default)
			)
			(layer "F.SilkS")
		)
		(fp_poly
			(pts
				(xy -0.9017 1.4351) (xy 0.9017 1.4351) (xy 0.9017 -1.4351) (xy -0.9017 -1.4351)
			)
			(stroke
				(width 0)
				(type default)
			)
			(fill no)
			(layer "F.CrtYd")
		)
		(fp_poly
			(pts
				(xy 0.9017 1.4351) (xy 0.9017 -1.4351) (xy -0.9017 -1.4351) (xy -0.9017 1.4351)
			)
			(stroke
				(width 0)
				(type default)
			)
			(fill no)
			(layer "F.Fab")
		)
		(pad "1" smd rect
			(at 0 -0.8382 180)
			(size 1.5494 0.9398)
			(layers "F.Cu" "F.Mask" "F.Paste")
			(net "PVCCP")
		)
		(pad "2" smd rect
			(at 0 0.8382 180)
			(size 1.5494 0.9398)
			(layers "F.Cu" "F.Mask" "F.Paste")
			(net "GND")
		)
	)
	(footprint ""
		(layer "F.Cu")
		(at 21.9964 -63.373 90)
		(property "Reference" "TP1"
			(at 0 0 90)
			(layer "F.SilkS")
			(hide yes)
			(effects
				(font
					(size 1.27 1.27)
				)
			)
		)
		(property "Value" "TPAD28-1-GP-U"
			(at 0.0508 -1.9304 90)
			(unlocked yes)
			(layer "F.Fab")
			(hide yes)
			(effects
				(font
					(size 1.016 1.016)
					(thickness 0.1524)
				)
			)
		)
		(property "Device Type" "TPAD28-1-U"
			(at 0.0508 -3.4544 90)
			(unlocked yes)
			(layer "F.Fab")
			(hide yes)
			(effects
				(font
					(size 1.016 1.016)
					(thickness 0.1524)
				)
			)
		)
		(duplicate_pad_numbers_are_jumpers no)
		(fp_poly
			(pts
				(arc
					(start 0 0.3556)
					(mid 0 -0.3556)
					(end 0 0.3556)
				)
			)
			(stroke
				(width 0)
				(type default)
			)
			(fill no)
			(layer "F.CrtYd")
		)
		(fp_poly
			(pts
				(arc
					(start 0 0.9525)
					(mid 0 -0.9525)
					(end 0 0.9525)
				)
			)
			(stroke
				(width 0)
				(type default)
			)
			(fill no)
			(layer "F.Fab")
		)
		(pad "1" smd circle
			(at 0 0 90)
			(size 0.7112 0.7112)
			(layers "F.Cu" "F.Mask" "F.Paste")
			(net "VR_PVNN_NTC")
		)
	)
	(footprint ""
		(layer "F.Cu")
		(at 47.117 -22.733 180)
		(property "Reference" "R480"
			(at 0 0 180)
			(layer "F.SilkS")
			(hide yes)
			(effects
				(font
					(size 1.27 1.27)
				)
			)
		)
		(property "Value" "4K7R2F-GP"
			(at 1.7907 -1.1176 180)
			(unlocked yes)
			(layer "F.Fab")
			(hide yes)
			(effects
				(font
					(size 1.016 1.016)
					(thickness 0.1524)
				)
			)
		)
		(property "Device Type" "R402H16"
			(at 1.7907 -2.6416 180)
			(unlocked yes)
			(layer "F.Fab")
			(hide yes)
			(effects
				(font
					(size 1.016 1.016)
					(thickness 0.1524)
				)
			)
		)
		(duplicate_pad_numbers_are_jumpers no)
		(fp_rect
			(start -0.381 0.8382)
			(end 0.381 -0.8382)
			(stroke
				(width 0)
				(type default)
			)
			(fill no)
			(layer "F.CrtYd")
		)
		(fp_rect
			(start -0.381 0.8382)
			(end 0.381 -0.8382)
			(stroke
				(width 0)
				(type default)
			)
			(fill no)
			(layer "F.Fab")
		)
		(pad "1" smd custom
			(at 0 -0.4318 180)
			(size 0.127 0.127)
			(layers "F.Cu" "F.Mask" "F.Paste")
			(net "P3V3_STBY")
			(options
				(clearance outline)
				(anchor circle)
			)
			(primitives
				(gr_poly
					(pts
						(arc
							(start -0.2032 -0.2794)
							(mid -0.239121 -0.264521)
							(end -0.254 -0.2286)
						)
						(arc
							(start -0.254 0.2286)
							(mid -0.239121 0.264521)
							(end -0.2032 0.2794)
						)
						(arc
							(start 0.2032 0.2794)
							(mid 0.239121 0.264521)
							(end 0.254 0.2286)
						)
						(arc
							(start 0.254 -0.2286)
							(mid 0.239121 -0.264521)
							(end 0.2032 -0.2794)
						)
					)
					(width 0)
					(fill yes)
				)
			)
		)
		(pad "2" smd custom
			(at 0 0.4318 180)
			(size 0.127 0.127)
			(layers "F.Cu" "F.Mask" "F.Paste")
			(net "BMC_PWRBTN#")
			(options
				(clearance outline)
				(anchor circle)
			)
			(primitives
				(gr_poly
					(pts
						(arc
							(start -0.2032 -0.2794)
							(mid -0.239121 -0.264521)
							(end -0.254 -0.2286)
						)
						(arc
							(start -0.254 0.2286)
							(mid -0.239121 0.264521)
							(end -0.2032 0.2794)
						)
						(arc
							(start 0.2032 0.2794)
							(mid 0.239121 0.264521)
							(end 0.254 0.2286)
						)
						(arc
							(start 0.254 -0.2286)
							(mid 0.239121 -0.264521)
							(end 0.2032 -0.2794)
						)
					)
					(width 0)
					(fill yes)
				)
			)
		)
	)
	(footprint ""
		(layer "F.Cu")
		(at 189.256416 -33.975802 90)
		(property "Reference" "PU10"
			(at 0 0 90)
			(layer "F.SilkS")
			(hide yes)
			(effects
				(font
					(size 1.27 1.27)
				)
			)
		)
		(property "Value" "ISL6353CRTZ-GP-U"
			(at -4.1783 -7.4422 90)
			(unlocked yes)
			(layer "F.Fab")
			(hide yes)
			(effects
				(font
					(size 1.016 1.016)
					(thickness 0.1524)
				)
			)
		)
		(property "Device Type" "QFN40-G3D5H32"
			(at -4.1783 -8.9662 90)
			(unlocked yes)
			(layer "F.Fab")
			(hide yes)
			(effects
				(font
					(size 1.016 1.016)
					(thickness 0.1524)
				)
			)
		)
		(duplicate_pad_numbers_are_jumpers no)
		(fp_poly
			(pts
				(xy 2.0574 -2.8829) (xy 2.8829 -2.8829) (xy 2.8829 -2.0574)
			)
			(stroke
				(width 0)
				(type default)
			)
			(fill yes)
			(layer "F.SilkS")
		)
		(fp_rect
			(start -2.8829 2.8829)
			(end 2.8829 -2.8829)
			(stroke
				(width 0)
				(type default)
			)
			(fill no)
			(layer "F.CrtYd")
		)
		(fp_rect
			(start -2.8829 2.8829)
			(end 2.8829 -2.8829)
			(stroke
				(width 0)
				(type default)
			)
			(fill no)
			(layer "F.Fab")
		)
		(pad "1" smd rect
			(at 1.800098 -2.4003 90)
			(size 0.2032 0.6604)
			(drill
				(offset 0 -0.0254)
			)
			(layers "F.Cu" "F.Mask" "F.Paste")
			(net "SVID_DIO_A")
		)
		(pad "2" smd rect
			(at 1.400048 -2.4003 90)
			(size 0.2032 0.7112)
			(layers "F.Cu" "F.Mask" "F.Paste")
			(net "SVID_A_ALERT#")
		)
		(pad "3" smd rect
			(at 0.999998 -2.4003 90)
			(size 0.2032 0.7112)
			(layers "F.Cu" "F.Mask" "F.Paste")
			(net "SVID_CLK_A")
		)
		(pad "4" smd rect
			(at 0.599948 -2.4003 90)
			(size 0.2032 0.7112)
			(layers "F.Cu" "F.Mask" "F.Paste")
			(net "VR_PWREN_PVDDR_A")
		)
		(pad "5" smd rect
			(at 0.199898 -2.4003 90)
			(size 0.2032 0.7112)
			(layers "F.Cu" "F.Mask" "F.Paste")
			(net "PWRGD_PVDDR_PG")
		)
		(pad "6" smd rect
			(at -0.199898 -2.4003 90)
			(size 0.2032 0.7112)
			(layers "F.Cu" "F.Mask" "F.Paste")
			(net "VR_PVDDR_A_IMON")
		)
		(pad "7" smd rect
			(at -0.599948 -2.4003 90)
			(size 0.2032 0.7112)
			(layers "F.Cu" "F.Mask" "F.Paste")
			(net "VR_PVDDR_PNN_VRHOT#")
		)
		(pad "8" smd rect
			(at -0.999998 -2.4003 90)
			(size 0.2032 0.7112)
			(layers "F.Cu" "F.Mask" "F.Paste")
			(net "VR_PVDDR_A_NTC")
		)
		(pad "9" smd rect
			(at -1.400048 -2.4003 90)
			(size 0.2032 0.7112)
			(layers "F.Cu" "F.Mask" "F.Paste")
			(net "VR_PVDDR_A_VW")
		)
		(pad "10" smd rect
			(at -1.800098 -2.4003 90)
			(size 0.2032 0.6604)
			(drill
				(offset 0 -0.0254)
			)
			(layers "F.Cu" "F.Mask" "F.Paste")
			(net "VR_PVDDR_A_COMP")
		)
		(pad "11" smd rect
			(at -2.4003 -1.800098 90)
			(size 0.6604 0.2032)
			(drill
				(offset -0.0254 0)
			)
			(layers "F.Cu" "F.Mask" "F.Paste")
			(net "VR_PVDDR_A_FB")
		)
		(pad "12" smd rect
			(at -2.4003 -1.400048 90)
			(size 0.7112 0.2032)
			(layers "F.Cu" "F.Mask" "F.Paste")
			(net "Net_320")
		)
		(pad "13" smd rect
			(at -2.4003 -0.999998 90)
			(size 0.7112 0.2032)
			(layers "F.Cu" "F.Mask" "F.Paste")
			(net "Net_321")
		)
		(pad "14" smd rect
			(at -2.4003 -0.599948 90)
			(size 0.7112 0.2032)
			(layers "F.Cu" "F.Mask" "F.Paste")
			(net "VR_PVDDR_A_ISEN2")
		)
		(pad "15" smd rect
			(at -2.4003 -0.199898 90)
			(size 0.7112 0.2032)
			(layers "F.Cu" "F.Mask" "F.Paste")
			(net "ISENSE_PVDDR_A_ISEN1")
		)
		(pad "16" smd rect
			(at -2.4003 0.199898 90)
			(size 0.7112 0.2032)
			(layers "F.Cu" "F.Mask" "F.Paste")
			(net "VR_PVDDR_A_VSEN")
		)
		(pad "17" smd rect
			(at -2.4003 0.599948 90)
			(size 0.7112 0.2032)
			(layers "F.Cu" "F.Mask" "F.Paste")
			(net "VSENSE_PVDDR_A_VRTN")
		)
		(pad "18" smd rect
			(at -2.4003 0.999998 90)
			(size 0.7112 0.2032)
			(layers "F.Cu" "F.Mask" "F.Paste")
			(net "VR_PVDDR_A_SUMN")
		)
		(pad "19" smd rect
			(at -2.4003 1.400048 90)
			(size 0.7112 0.2032)
			(layers "F.Cu" "F.Mask" "F.Paste")
			(net "VR_PVDDRA_ISUMP1")
		)
		(pad "20" smd rect
			(at -2.4003 1.800098 90)
			(size 0.6604 0.2032)
			(drill
				(offset -0.0254 0)
			)
			(layers "F.Cu" "F.Mask" "F.Paste")
			(net "VR_PVDDR_A_VDD")
		)
		(pad "21" smd rect
			(at -1.800098 2.4003 90)
			(size 0.2032 0.6604)
			(drill
				(offset 0 0.0254)
			)
			(layers "F.Cu" "F.Mask" "F.Paste")
			(net "VR_PVDDR_A_VIN")
		)
		(pad "22" smd rect
			(at -1.400048 2.4003 90)
			(size 0.2032 0.7112)
			(layers "F.Cu" "F.Mask" "F.Paste")
			(net "VR_PVDDR_A_PROG1")
		)
		(pad "23" smd rect
			(at -0.999998 2.4003 90)
			(size 0.2032 0.7112)
			(layers "F.Cu" "F.Mask" "F.Paste")
			(net "VR_PVDDR_A_BOOT1")
		)
		(pad "24" smd rect
			(at -0.599948 2.4003 90)
			(size 0.2032 0.7112)
			(layers "F.Cu" "F.Mask" "F.Paste")
			(net "VR_PVDDR_A_GH1")
		)
		(pad "25" smd rect
			(at -0.199898 2.4003 90)
			(size 0.2032 0.7112)
			(layers "F.Cu" "F.Mask" "F.Paste")
			(net "VR_PVDDR_A_PHASE1")
		)
		(pad "26" smd rect
			(at 0.199898 2.4003 90)
			(size 0.2032 0.7112)
			(layers "F.Cu" "F.Mask" "F.Paste")
			(net "GND")
		)
		(pad "27" smd rect
			(at 0.599948 2.4003 90)
			(size 0.2032 0.7112)
			(layers "F.Cu" "F.Mask" "F.Paste")
			(net "VR_PVDDR_A_GL1")
		)
		(pad "28" smd rect
			(at 0.999998 2.4003 90)
			(size 0.2032 0.7112)
			(layers "F.Cu" "F.Mask" "F.Paste")
			(net "VR_PVDDR_A_PWM3")
		)
		(pad "29" smd rect
			(at 1.400048 2.4003 90)
			(size 0.2032 0.7112)
			(layers "F.Cu" "F.Mask" "F.Paste")
			(net "VR_PVDDR_A_VDDP")
		)
		(pad "30" smd rect
			(at 1.800098 2.4003 90)
			(size 0.2032 0.6604)
			(drill
				(offset 0 0.0254)
			)
			(layers "F.Cu" "F.Mask" "F.Paste")
			(net "Net_316")
		)
		(pad "31" smd rect
			(at 2.4003 1.800098 90)
			(size 0.6604 0.2032)
			(drill
				(offset 0.0254 0)
			)
			(layers "F.Cu" "F.Mask" "F.Paste")
			(net "GND")
		)
		(pad "32" smd rect
			(at 2.4003 1.400048 90)
			(size 0.7112 0.2032)
			(layers "F.Cu" "F.Mask" "F.Paste")
			(net "Net_318")
		)
		(pad "33" smd rect
			(at 2.4003 0.999998 90)
			(size 0.7112 0.2032)
			(layers "F.Cu" "F.Mask" "F.Paste")
			(net "Net_319")
		)
		(pad "34" smd rect
			(at 2.4003 0.599948 90)
			(size 0.7112 0.2032)
			(layers "F.Cu" "F.Mask" "F.Paste")
			(net "Net_317")
		)
		(pad "35" smd rect
			(at 2.4003 0.199898 90)
			(size 0.7112 0.2032)
			(layers "F.Cu" "F.Mask" "F.Paste")
			(net "VR_PVDDR_A_PROG2")
		)
		(pad "36" smd rect
			(at 2.4003 -0.199898 90)
			(size 0.7112 0.2032)
			(layers "F.Cu" "F.Mask" "F.Paste")
			(net "VR_PVDDR_A_PSI")
		)
		(pad "37" smd rect
			(at 2.4003 -0.599948 90)
			(size 0.7112 0.2032)
			(layers "F.Cu" "F.Mask" "F.Paste")
			(net "VR_PVDDR_A_VAUTO")
		)
		(pad "38" smd rect
			(at 2.4003 -0.999998 90)
			(size 0.7112 0.2032)
			(layers "F.Cu" "F.Mask" "F.Paste")
			(net "VR_PVDDR_A_IAUTO")
		)
		(pad "39" smd rect
			(at 2.4003 -1.400048 90)
			(size 0.7112 0.2032)
			(layers "F.Cu" "F.Mask" "F.Paste")
			(net "VR_PVDDR_A_OCP")
		)
		(pad "40" smd rect
			(at 2.4003 -1.800098 90)
			(size 0.6604 0.2032)
			(drill
				(offset 0.0254 0)
			)
			(layers "F.Cu" "F.Mask" "F.Paste")
			(net "VR_PVDDR_A_SVID_ADDR")
		)
		(pad "41" smd rect
			(at 0 0 90)
			(size 3.5052 3.5052)
			(layers "F.Cu" "F.Mask" "F.Paste")
			(net "GND")
		)
	)
)
